(kicad_pcb
	(version 20221018)
	(generator pcbnew)
	(general
    (thickness 1.62)
  )
	(paper "A4")
	(title_block
    (title "ECP5 - Datacenter Secure Control Module (DC-SCM)")
    (date "2024-07-01")
    (rev "1.2.1")
		(comment 9 "footprints 46-49 of 506")
	)
	(layers
    (0 "F.Cu" signal)
    (1 "In1.Cu" power)
    (2 "In2.Cu" signal)
    (3 "In3.Cu" power)
    (4 "In4.Cu" power)
    (5 "In5.Cu" signal)
    (6 "In6.Cu" power)
    (31 "B.Cu" signal)
    (32 "B.Adhes" user "B.Adhesive")
    (33 "F.Adhes" user "F.Adhesive")
    (34 "B.Paste" user)
    (35 "F.Paste" user)
    (36 "B.SilkS" user "B.Silkscreen")
    (37 "F.SilkS" user "F.Silkscreen")
    (38 "B.Mask" user)
    (39 "F.Mask" user)
    (40 "Dwgs.User" user "User.Drawings")
    (41 "Cmts.User" user "User.Comments")
    (42 "Eco1.User" user "User.Eco1")
    (43 "Eco2.User" user "User.Eco2")
    (44 "Edge.Cuts" user)
    (45 "Margin" user)
    (46 "B.CrtYd" user "B.Courtyard")
    (47 "F.CrtYd" user "F.Courtyard")
    (48 "B.Fab" user)
    (49 "F.Fab" user)
  )
	(footprint "antmicro-footprints:SOT-23-3" (layer "F.Cu")
    (at 124.2 72.45)
    (property "Author" "Antmicro")
    (property "License" "Apache-2.0")
    (property "MPN" "2N7002")
    (property "Manufacturer" "ON Semiconductor")
    (property "Sheetfile" "interfaces.kicad_sch")
    (property "Sheetname" "Interfaces")
    (property "ki_description" "Power MOSFET, N Channel, 60 V, 115 mA, 1.2 ohm, SOT-23, Surface Mount")
    (property "ki_keywords" "SMT, TRANSISTOR, SEMICONDUCTOR, NMOS")
    (attr smd)
    (fp_text reference "Q3" (at 2.525 1.2 90) (layer "F.SilkS")
        (effects (font (size 0.7 0.7) (thickness 0.127)))
    )
    (fp_text value "2N7002_SOT-23-3" (at 0.025 3.25) (layer "F.Fab")
        (effects (font (size 1 1) (thickness 0.15)))
    )
    (fp_text user "License: Apache-2.0" (at -1.8 6.8) (layer "F.Fab") hide
        (effects (font (size 0.7 0.7) (thickness 0.15)) (justify left bottom))
    )
    (fp_text user "Author: Antmicro" (at -1.837 5.3) (layer "F.Fab") hide
        (effects (font (size 0.7 0.7) (thickness 0.15)) (justify left bottom))
    )
    (fp_text user "${REFERENCE}" (at -0.125 0.15) (layer "F.Fab")
        (effects (font (size 0.25 0.25) (thickness 0.05)))
    )
    (fp_line (start -1.45 -1.35) (end -0.85 -1.35)
      (stroke (width 0.15) (type solid)) (layer "F.SilkS"))
    (fp_line (start -0.85 -1.35) (end -0.7 -1.5)
      (stroke (width 0.15) (type solid)) (layer "F.SilkS"))
    (fp_line (start -0.7 1.5) (end -0.7 1.35)
      (stroke (width 0.15) (type solid)) (layer "F.SilkS"))
    (fp_line (start 0.7 -1.5) (end -0.7 -1.5)
      (stroke (width 0.15) (type solid)) (layer "F.SilkS"))
    (fp_line (start 0.7 -0.4) (end 0.7 -1.5)
      (stroke (width 0.15) (type solid)) (layer "F.SilkS"))
    (fp_line (start 0.7 0.4) (end 0.7 1.5)
      (stroke (width 0.15) (type solid)) (layer "F.SilkS"))
    (fp_line (start 0.7 1.5) (end -0.7 1.5)
      (stroke (width 0.15) (type solid)) (layer "F.SilkS"))
    (fp_line (start -1.75 -0.5) (end -1.75 -1.4)
      (stroke (width 0.05) (type solid)) (layer "F.CrtYd"))
    (fp_line (start -1.75 0.5) (end -0.85 0.5)
      (stroke (width 0.05) (type solid)) (layer "F.CrtYd"))
    (fp_line (start -1.75 1.4) (end -1.75 0.5)
      (stroke (width 0.05) (type solid)) (layer "F.CrtYd"))
    (fp_line (start -0.9 -1.6) (end -0.9 -1.4)
      (stroke (width 0.05) (type solid)) (layer "F.CrtYd"))
    (fp_line (start -0.9 -1.6) (end 0.825 -1.6)
      (stroke (width 0.05) (type solid)) (layer "F.CrtYd"))
    (fp_line (start -0.9 -1.4) (end -1.75 -1.4)
      (stroke (width 0.05) (type solid)) (layer "F.CrtYd"))
    (fp_line (start -0.85 -0.5) (end -1.75 -0.5)
      (stroke (width 0.05) (type solid)) (layer "F.CrtYd"))
    (fp_line (start -0.85 0.5) (end -0.85 -0.5)
      (stroke (width 0.05) (type solid)) (layer "F.CrtYd"))
    (fp_line (start -0.85 1.4) (end -1.75 1.4)
      (stroke (width 0.05) (type solid)) (layer "F.CrtYd"))
    (fp_line (start -0.85 1.65) (end -0.85 1.4)
      (stroke (width 0.05) (type solid)) (layer "F.CrtYd"))
    (fp_line (start 0.825 -1.6) (end 0.825 -0.45)
      (stroke (width 0.05) (type solid)) (layer "F.CrtYd"))
    (fp_line (start 0.825 -0.45) (end 1.75 -0.45)
      (stroke (width 0.05) (type solid)) (layer "F.CrtYd"))
    (fp_line (start 0.85 0.45) (end 0.85 1.65)
      (stroke (width 0.05) (type solid)) (layer "F.CrtYd"))
    (fp_line (start 0.85 1.65) (end -0.85 1.65)
      (stroke (width 0.05) (type solid)) (layer "F.CrtYd"))
    (fp_line (start 1.75 -0.45) (end 1.75 0.45)
      (stroke (width 0.05) (type solid)) (layer "F.CrtYd"))
    (fp_line (start 1.75 0.45) (end 0.85 0.45)
      (stroke (width 0.05) (type solid)) (layer "F.CrtYd"))
    (fp_line (start -0.712 -1.325) (end -0.712 1.523)
      (stroke (width 0.15) (type solid)) (layer "F.Fab"))
    (fp_line (start -0.712 1.519) (end 0.688 1.519)
      (stroke (width 0.15) (type solid)) (layer "F.Fab"))
    (fp_line (start -0.437 -1.526) (end -0.712 -1.325)
      (stroke (width 0.15) (type solid)) (layer "F.Fab"))
    (fp_line (start -0.437 -1.526) (end 0.688 -1.526)
      (stroke (width 0.15) (type solid)) (layer "F.Fab"))
    (fp_line (start 0.688 1.519) (end 0.688 -1.52)
      (stroke (width 0.15) (type solid)) (layer "F.Fab"))
    (pad "1" smd roundrect (at -1.1 -0.951) (size 1 0.6) (layers "F.Cu" "F.Paste" "F.Mask") (roundrect_rratio 0.15)
      (net 295 "USR_LED2") (pinfunction "G") (pintype "passive"))
    (pad "2" smd roundrect (at -1.1 0.949) (size 1 0.6) (layers "F.Cu" "F.Paste" "F.Mask") (roundrect_rratio 0.15)
      (net 1 "GND") (pinfunction "S") (pintype "passive"))
    (pad "3" smd roundrect (at 1.1 -0.0005) (size 1 0.6) (layers "F.Cu" "F.Paste" "F.Mask") (roundrect_rratio 0.15)
      (net 313 "Net-(D5-C)") (pinfunction "D") (pintype "passive"))
  )
	(footprint "antmicro-footprints:R_0402_1005Metric" (layer "F.Cu")
    (at 138.1 64.25 -90)
    (descr "Resistor SMD 0402")
    (tags "resistor SMD 0402")
    (property "Author" "Antmicro")
    (property "License" "Apache-2.0")
    (property "MPN" "CR0402-FX-1101GLF")
    (property "Manufacturer" "Bourns")
    (property "Public" "False")
    (property "Sheetfile" "interfaces.kicad_sch")
    (property "Sheetname" "Interfaces")
    (property "Tolerance" "1%")
    (property "Val" "1k1")
    (property "ki_description" "SMD Chip Resistor")
    (property "ki_keywords" "0402, SMT, RESISTOR, PASSIVE")
    (attr smd)
    (fp_text reference "R69" (at 0 1.05 90) (layer "F.SilkS")
        (effects (font (size 0.7 0.7) (thickness 0.127)))
    )
    (fp_text value "R_1k1_0402" (at 0 1.17 90) (layer "F.Fab")
        (effects (font (size 1 1) (thickness 0.15)))
    )
    (fp_text user "${REFERENCE}" (at 0 0 90) (layer "F.Fab")
        (effects (font (size 0.25 0.25) (thickness 0.04)))
    )
    (fp_text user "Author: Antmicro" (at -0.95 4.169 -90) (layer "F.Fab") hide
        (effects (font (size 0.7 0.7) (thickness 0.15)) (justify left bottom))
    )
    (fp_text user "License: Apache-2.0" (at -0.95 5.169 -90) (layer "F.Fab") hide
        (effects (font (size 0.7 0.7) (thickness 0.15)) (justify left bottom))
    )
    (fp_rect (start -0.925 -0.47) (end 0.925 0.47)
      (stroke (width 0.05) (type default)) (fill none) (layer "F.CrtYd"))
    (fp_rect (start -0.5 -0.25) (end 0.5 0.25)
      (stroke (width 0.15) (type solid)) (fill none) (layer "F.Fab"))
    (pad "1" smd roundrect (at -0.48 0 270) (size 0.59 0.64) (layers "F.Cu" "F.Paste" "F.Mask") (roundrect_rratio 0.25)
      (net 310 "Net-(D3-A)") (pintype "passive"))
    (pad "2" smd roundrect (at 0.48 0 270) (size 0.59 0.64) (layers "F.Cu" "F.Paste" "F.Mask") (roundrect_rratio 0.25)
      (net 2 "VCC3V3") (pintype "passive"))
  )
	(footprint "antmicro-footprints:R_0402_1005Metric" (layer "F.Cu")
    (at 140.15 64.25 -90)
    (descr "Resistor SMD 0402")
    (tags "resistor SMD 0402")
    (property "Author" "Antmicro")
    (property "License" "Apache-2.0")
    (property "MPN" "CR0402-FX-1101GLF")
    (property "Manufacturer" "Bourns")
    (property "Public" "False")
    (property "Sheetfile" "interfaces.kicad_sch")
    (property "Sheetname" "Interfaces")
    (property "Tolerance" "1%")
    (property "Val" "1k1")
    (property "ki_description" "SMD Chip Resistor")
    (property "ki_keywords" "0402, SMT, RESISTOR, PASSIVE")
    (attr smd)
    (fp_text reference "R70" (at 0 0.9 -90) (layer "F.SilkS")
        (effects (font (size 0.7 0.7) (thickness 0.127)))
    )
    (fp_text value "R_1k1_0402" (at 0 1.17 -90) (layer "F.Fab")
        (effects (font (size 1 1) (thickness 0.15)))
    )
    (fp_text user "License: Apache-2.0" (at -0.95 5.169 -90) (layer "F.Fab") hide
        (effects (font (size 0.7 0.7) (thickness 0.15)) (justify left bottom))
    )
    (fp_text user "${REFERENCE}" (at 0 0 -90) (layer "F.Fab")
        (effects (font (size 0.25 0.25) (thickness 0.04)))
    )
    (fp_text user "Author: Antmicro" (at -0.95 4.169 -90) (layer "F.Fab") hide
        (effects (font (size 0.7 0.7) (thickness 0.15)) (justify left bottom))
    )
    (fp_rect (start -0.925 -0.47) (end 0.925 0.47)
      (stroke (width 0.05) (type default)) (fill none) (layer "F.CrtYd"))
    (fp_rect (start -0.5 -0.25) (end 0.5 0.25)
      (stroke (width 0.15) (type solid)) (fill none) (layer "F.Fab"))
    (pad "1" smd roundrect (at -0.48 0 270) (size 0.59 0.64) (layers "F.Cu" "F.Paste" "F.Mask") (roundrect_rratio 0.25)
      (net 312 "Net-(D4-A)") (pintype "passive"))
    (pad "2" smd roundrect (at 0.48 0 270) (size 0.59 0.64) (layers "F.Cu" "F.Paste" "F.Mask") (roundrect_rratio 0.25)
      (net 2 "VCC3V3") (pintype "passive"))
  )
	(footprint "antmicro-footprints:R_0402_1005Metric" (layer "F.Cu")
    (at 142.2 64.25 -90)
    (descr "Resistor SMD 0402")
    (tags "resistor SMD 0402")
    (property "Author" "Antmicro")
    (property "License" "Apache-2.0")
    (property "MPN" "CR0402-FX-1101GLF")
    (property "Manufacturer" "Bourns")
    (property "Public" "False")
    (property "Sheetfile" "interfaces.kicad_sch")
    (property "Sheetname" "Interfaces")
    (property "Tolerance" "1%")
    (property "Val" "1k1")
    (property "ki_description" "SMD Chip Resistor")
    (property "ki_keywords" "0402, SMT, RESISTOR, PASSIVE")
    (attr smd)
    (fp_text reference "R71" (at 0 0.95 90) (layer "F.SilkS")
        (effects (font (size 0.7 0.7) (thickness 0.127)))
    )
    (fp_text value "R_1k1_0402" (at 0 1.17 90) (layer "F.Fab")
        (effects (font (size 1 1) (thickness 0.15)))
    )
    (fp_text user "License: Apache-2.0" (at -0.95 5.169 -90) (layer "F.Fab") hide
        (effects (font (size 0.7 0.7) (thickness 0.15)) (justify left bottom))
    )
    (fp_text user "${REFERENCE}" (at 0 0 90) (layer "F.Fab")
        (effects (font (size 0.25 0.25) (thickness 0.04)))
    )
    (fp_text user "Author: Antmicro" (at -0.95 4.169 -90) (layer "F.Fab") hide
        (effects (font (size 0.7 0.7) (thickness 0.15)) (justify left bottom))
    )
    (fp_rect (start -0.925 -0.47) (end 0.925 0.47)
      (stroke (width 0.05) (type default)) (fill none) (layer "F.CrtYd"))
    (fp_rect (start -0.5 -0.25) (end 0.5 0.25)
      (stroke (width 0.15) (type solid)) (fill none) (layer "F.Fab"))
    (pad "1" smd roundrect (at -0.48 0 270) (size 0.59 0.64) (layers "F.Cu" "F.Paste" "F.Mask") (roundrect_rratio 0.25)
      (net 314 "Net-(D5-A)") (pintype "passive"))
    (pad "2" smd roundrect (at 0.48 0 270) (size 0.59 0.64) (layers "F.Cu" "F.Paste" "F.Mask") (roundrect_rratio 0.25)
      (net 2 "VCC3V3") (pintype "passive"))
  )
)
